# TIMECARD (Time Appliance Project (Time Card)) — schematic netlist excerpt (pin names and nets, part order shuffled) for the footprints in the layout excerpt that follows; sources: Cadence DE-HDL packaged netlist, KiCad conversion of R4006-B0001-02_R01.brd

R42  RESISTOR  0OHM -  pkg SMC_0402R_H016  page 9 : \1\ = PCIE_CONN_TDO ; \2\ = FPGA_TDO
R118  RESISTOR  330OHM 1%  pkg SMC_0402R_H016  page 26 : \1\ = UNNAMED_14_OPTICAL_I191_A ; \2\ = XP3R3V_PCIE

(kicad_pcb
	(version 20260206)
	(generator "pcbnew")
	(generator_version "10.0")
	(general
		(thickness 1.6)
		(legacy_teardrops no)
	)
	(paper "A4")
	(title_block
		(title "timecard-production-celestica-r4006 — R4006-B0001-02_R01.brd")
		(comment 1 "Time Appliance Project (Time Card) / footprints 700-701 of 1113")
	)
	(layers
		(0 "F.Cu" signal "TOP")
		(4 "In1.Cu" signal "L02_GND1")
		(6 "In2.Cu" signal "L03_SIG1")
		(8 "In3.Cu" signal "L04_GND2")
		(10 "In4.Cu" signal "L05_VCC1")
		(12 "In5.Cu" signal "L06_VCC2")
		(14 "In6.Cu" signal "L07_GND3")
		(16 "In7.Cu" signal "L08_SIG2")
		(18 "In8.Cu" signal "L09_GND4")
		(2 "B.Cu" signal "BOTTOM")
		(9 "F.Adhes" user "F.Adhesive")
		(11 "B.Adhes" user "B.Adhesive")
		(13 "F.Paste" user "Package Geometry/Pastemask Top")
		(15 "B.Paste" user "Package Geometry/Pastemask Bottom")
		(5 "F.SilkS" user "Ref Des/Silkscreen Top")
		(7 "B.SilkS" user "Ref Des/Silkscreen Bottom")
		(1 "F.Mask" user "Board Geometry/Soldermask Top")
		(3 "B.Mask" user "Board Geometry/Soldermask Bottom")
		(17 "Dwgs.User" user "User.Drawings")
		(19 "Cmts.User" user "User.Comments")
		(21 "Eco1.User" user "User.Eco1")
		(23 "Eco2.User" user "User.Eco2")
		(25 "Edge.Cuts" user "Board Geometry/Outline")
		(27 "Margin" user)
		(31 "F.CrtYd" user "Package Geometry/Place Bound Top")
		(29 "B.CrtYd" user "Package Geometry/Place Bound Bottom")
		(35 "F.Fab" user "Ref Des/Assembly Top")
		(33 "B.Fab" user "Ref Des/Assembly Bottom")
	)
	(footprint ""
		(layer "B.Cu")
		(at 150.114 -104.394 90)
		(property "Reference" "R118"
			(at -1.397 1.10363 270)
			(unlocked yes)
			(layer "B.SilkS")
			(effects
				(font
					(size 0.7874 0.5842)
					(thickness 0.1524)
				)
				(justify mirror)
			)
		)
		(property "Value" "VAL*"
			(at -0.02032 2.13233 90)
			(unlocked yes)
			(layer "B.Fab")
			(hide yes)
			(effects
				(font
					(size 0.7874 0.5842)
					(thickness 0.1524)
				)
				(justify mirror)
			)
		)
		(property "Tolerance" "TOL*"
			(at -0.044704 3.05435 90)
			(unlocked yes)
			(layer "Cmts.User")
			(hide yes)
			(effects
				(font
					(size 0.7874 0.5842)
					(thickness 0.1524)
				)
				(justify mirror)
			)
		)
		(property "User Part Number" "PARTNUM*"
			(at -0.02032 4.024884 90)
			(unlocked yes)
			(layer "Cmts.User")
			(hide yes)
			(effects
				(font
					(size 0.7874 0.5842)
					(thickness 0.1524)
				)
				(justify mirror)
			)
		)
		(property "Device Type" "RESISTOR-G155-13300-01,330OHM,A"
			(at -0.008382 1.210564 90)
			(unlocked yes)
			(layer "B.Fab")
			(hide yes)
			(effects
				(font
					(size 0.7874 0.5842)
					(thickness 0.1524)
				)
				(justify mirror)
			)
		)
		(duplicate_pad_numbers_are_jumpers no)
		(fp_line
			(start 1.143 -0.5588)
			(end 1.143 0.5588)
			(stroke
				(width 0.1)
				(type default)
			)
			(layer "B.SilkS")
		)
		(fp_line
			(start -1.143 -0.5588)
			(end 1.143 -0.5588)
			(stroke
				(width 0.1)
				(type default)
			)
			(layer "B.SilkS")
		)
		(fp_line
			(start 1.143 0.5588)
			(end -1.143 0.5588)
			(stroke
				(width 0.1)
				(type default)
			)
			(layer "B.SilkS")
		)
		(fp_line
			(start -1.143 0.5588)
			(end -1.143 -0.5588)
			(stroke
				(width 0.1)
				(type default)
			)
			(layer "B.SilkS")
		)
		(fp_poly
			(pts
				(xy 1.143 0.5588) (xy -1.143 0.5588) (xy -1.143 -0.5588) (xy 1.143 -0.5588)
			)
			(stroke
				(width 0)
				(type default)
			)
			(fill no)
			(layer "B.CrtYd")
		)
		(fp_line
			(start 0.508 -0.3048)
			(end 0.508 0.3048)
			(stroke
				(width 0.1)
				(type default)
			)
			(layer "B.Fab")
		)
		(fp_line
			(start -0.508 -0.3048)
			(end 0.508 -0.3048)
			(stroke
				(width 0.1)
				(type default)
			)
			(layer "B.Fab")
		)
		(fp_line
			(start 0.508 0.3048)
			(end -0.508 0.3048)
			(stroke
				(width 0.1)
				(type default)
			)
			(layer "B.Fab")
		)
		(fp_line
			(start -0.508 0.3048)
			(end -0.508 -0.3048)
			(stroke
				(width 0.1)
				(type default)
			)
			(layer "B.Fab")
		)
		(pad "1" smd rect
			(at 0.5334 0 270)
			(size 0.7112 0.6096)
			(layers "B.Cu" "B.Mask" "B.Paste")
			(net "UNNAMED_14_OPTICAL_I191_A")
		)
		(pad "2" smd rect
			(at -0.5334 0 270)
			(size 0.7112 0.6096)
			(layers "B.Cu" "B.Mask" "B.Paste")
			(net "XP3R3V_PCIE")
		)
		(zone
			(layer "B.Cu")
			(hatch none 0.5)
			(connect_pads
				(clearance 0)
			)
			(min_thickness 0.25)
			(keepout
				(tracks allowed)
				(vias not_allowed)
				(pads allowed)
				(copperpour not_allowed)
				(footprints allowed)
			)
			(placement
				(enabled no)
				(sheetname "")
			)
			(fill
				(thermal_gap 0.5)
				(thermal_bridge_width 0.5)
				(island_removal_mode 0)
			)
			(polygon
				(pts
					(xy 150.4188 -104.4702) (xy 149.8092 -104.4702) (xy 149.8092 -104.3178) (xy 150.4188 -104.3178)
				)
			)
		)
		(zone
			(layer "B.Cu")
			(hatch none 0.5)
			(connect_pads
				(clearance 0)
			)
			(min_thickness 0.25)
			(keepout
				(tracks not_allowed)
				(vias allowed)
				(pads allowed)
				(copperpour not_allowed)
				(footprints allowed)
			)
			(placement
				(enabled no)
				(sheetname "")
			)
			(fill
				(thermal_gap 0.5)
				(thermal_bridge_width 0.5)
				(island_removal_mode 0)
			)
			(polygon
				(pts
					(xy 150.4188 -104.4702) (xy 149.8092 -104.4702) (xy 149.8092 -104.3178) (xy 150.4188 -104.3178)
				)
			)
		)
	)
	(footprint ""
		(layer "B.Cu")
		(at 140.335 -71.501)
		(property "Reference" "R42"
			(at -4.191 -0.21463 0)
			(unlocked yes)
			(layer "B.SilkS")
			(effects
				(font
					(size 0.7874 0.5842)
					(thickness 0.1524)
				)
				(justify mirror)
			)
		)
		(property "Value" "VAL*"
			(at -0.02032 2.13233 0)
			(unlocked yes)
			(layer "B.Fab")
			(hide yes)
			(effects
				(font
					(size 0.7874 0.5842)
					(thickness 0.1524)
				)
				(justify mirror)
			)
		)
		(property "Tolerance" "TOL*"
			(at -0.044704 3.05435 0)
			(unlocked yes)
			(layer "Cmts.User")
			(hide yes)
			(effects
				(font
					(size 0.7874 0.5842)
					(thickness 0.1524)
				)
				(justify mirror)
			)
		)
		(property "User Part Number" "PARTNUM*"
			(at -0.02032 4.024884 0)
			(unlocked yes)
			(layer "Cmts.User")
			(hide yes)
			(effects
				(font
					(size 0.7874 0.5842)
					(thickness 0.1524)
				)
				(justify mirror)
			)
		)
		(property "Device Type" "RESISTOR-G155-100R0-J0,0OHM,-"
			(at -0.008382 1.210564 0)
			(unlocked yes)
			(layer "B.Fab")
			(hide yes)
			(effects
				(font
					(size 0.7874 0.5842)
					(thickness 0.1524)
				)
				(justify mirror)
			)
		)
		(duplicate_pad_numbers_are_jumpers no)
		(fp_line
			(start -1.143 -0.5588)
			(end 1.143 -0.5588)
			(stroke
				(width 0.1)
				(type default)
			)
			(layer "B.SilkS")
		)
		(fp_line
			(start -1.143 0.5588)
			(end -1.143 -0.5588)
			(stroke
				(width 0.1)
				(type default)
			)
			(layer "B.SilkS")
		)
		(fp_line
			(start 1.143 -0.5588)
			(end 1.143 0.5588)
			(stroke
				(width 0.1)
				(type default)
			)
			(layer "B.SilkS")
		)
		(fp_line
			(start 1.143 0.5588)
			(end -1.143 0.5588)
			(stroke
				(width 0.1)
				(type default)
			)
			(layer "B.SilkS")
		)
		(fp_rect
			(start 1.143 0.5588)
			(end -1.143 -0.5588)
			(stroke
				(width 0)
				(type default)
			)
			(fill no)
			(layer "B.CrtYd")
		)
		(fp_line
			(start -0.508 -0.3048)
			(end 0.508 -0.3048)
			(stroke
				(width 0.1)
				(type default)
			)
			(layer "B.Fab")
		)
		(fp_line
			(start -0.508 0.3048)
			(end -0.508 -0.3048)
			(stroke
				(width 0.1)
				(type default)
			)
			(layer "B.Fab")
		)
		(fp_line
			(start 0.508 -0.3048)
			(end 0.508 0.3048)
			(stroke
				(width 0.1)
				(type default)
			)
			(layer "B.Fab")
		)
		(fp_line
			(start 0.508 0.3048)
			(end -0.508 0.3048)
			(stroke
				(width 0.1)
				(type default)
			)
			(layer "B.Fab")
		)
		(pad "1" smd rect
			(at 0.5334 0 180)
			(size 0.7112 0.6096)
			(layers "B.Cu" "B.Mask" "B.Paste")
			(net "PCIE_CONN_TDO")
		)
		(pad "2" smd rect
			(at -0.5334 0 180)
			(size 0.7112 0.6096)
			(layers "B.Cu" "B.Mask" "B.Paste")
			(net "FPGA_TDO")
		)
		(zone
			(layer "B.Cu")
			(hatch none 0.5)
			(connect_pads
				(clearance 0)
			)
			(min_thickness 0.25)
			(keepout
				(tracks allowed)
				(vias not_allowed)
				(pads allowed)
				(copperpour not_allowed)
				(footprints allowed)
			)
			(placement
				(enabled no)
				(sheetname "")
			)
			(fill
				(thermal_gap 0.5)
				(thermal_bridge_width 0.5)
				(island_removal_mode 0)
			)
			(polygon
				(pts
					(xy 140.4112 -71.1962) (xy 140.4112 -71.8058) (xy 140.2588 -71.8058) (xy 140.2588 -71.1962)
				)
			)
		)
	)
)
